# BASEBOARD_FAB2 (Tioga Pass) — schematic netlist excerpt (pin names and nets, part order shuffled) for the footprints in the layout excerpt that follows; sources: Cadence DE-HDL packaged netlist, KiCad conversion of Wiwynn_Tioga_Pass_MB.brd

RF21  RES  1.0K 0.1% CHIP  pkg 0402  page 226 : A = VR_PVDDQ_KLM_AIREF1 ; B = ISENSE_PVDDQ_KLM_PH1_IMON
R1D22  RES  10.0K 1% CHIP  pkg 0402  page 200 : A = P3V3_STBY ; B = FM_OC_DETECT_N
C8G1  CAP  0.22UF 16V 10% X7R  pkg 0402  page 105 : A = P3E_CPU0_PE2_SS_TXP<4> ; B = P3E_CPU0_PE2_SS_C_TXP<4>

(kicad_pcb
	(version 20260206)
	(generator "pcbnew")
	(generator_version "10.0")
	(general
		(thickness 1.6)
		(legacy_teardrops no)
	)
	(paper "A4")
	(title_block
		(title "Wiwynn_Tioga_Pass_MB.brd")
		(comment 1 "Tioga Pass / footprints 314-316 of 4770")
	)
	(layers
		(0 "F.Cu" signal "TOP")
		(4 "In1.Cu" signal "L2GND")
		(6 "In2.Cu" signal "L3")
		(8 "In3.Cu" signal "L4GND")
		(10 "In4.Cu" signal "L5")
		(12 "In5.Cu" signal "L6GND")
		(14 "In6.Cu" signal "L7VCC")
		(16 "In7.Cu" signal "L8VCC")
		(18 "In8.Cu" signal "L9GND")
		(20 "In9.Cu" signal "L10")
		(22 "In10.Cu" signal "L11GND")
		(24 "In11.Cu" signal "L12")
		(26 "In12.Cu" signal "L13GND")
		(2 "B.Cu" signal "BOTTOM")
		(9 "F.Adhes" user "F.Adhesive")
		(11 "B.Adhes" user "B.Adhesive")
		(13 "F.Paste" user "Package Geometry/Pastemask Top")
		(15 "B.Paste" user "Package Geometry/Pastemask Bottom")
		(5 "F.SilkS" user "Ref Des/Silkscreen Top")
		(7 "B.SilkS" user "Ref Des/Silkscreen Bottom")
		(1 "F.Mask" user "Board Geometry/Soldermask Top")
		(3 "B.Mask" user "Board Geometry/Soldermask Bottom")
		(17 "Dwgs.User" user "User.Drawings")
		(19 "Cmts.User" user "User.Comments")
		(21 "Eco1.User" user "User.Eco1")
		(23 "Eco2.User" user "User.Eco2")
		(25 "Edge.Cuts" user "Board Geometry/Outline")
		(27 "Margin" user)
		(31 "F.CrtYd" user "Package Geometry/Place Bound Top")
		(29 "B.CrtYd" user "Package Geometry/Place Bound Bottom")
		(35 "F.Fab" user "Ref Des/Assembly Top")
		(33 "B.Fab" user "Ref Des/Assembly Bottom")
	)
	(footprint ""
		(layer "F.Cu")
		(at 26.289 -81.026 180)
		(property "Reference" "R1D22"
			(at 0 0 180)
			(layer "F.SilkS")
			(hide yes)
			(effects
				(font
					(size 1.27 1.27)
				)
			)
		)
		(property "Value" ""
			(at 0 0 180)
			(layer "F.Fab")
			(effects
				(font
					(size 1.27 1.27)
				)
			)
		)
		(duplicate_pad_numbers_are_jumpers no)
		(fp_poly
			(pts
				(xy -0.2794 -0.1016) (xy 0.2794 -0.1016) (xy 0.2794 0.9906) (xy -0.2794 0.9906)
			)
			(stroke
				(width 0)
				(type default)
			)
			(fill no)
			(layer "F.CrtYd")
		)
		(fp_line
			(start 0.2794 0.9906)
			(end 0.2794 -0.1016)
			(stroke
				(width 0.1)
				(type default)
			)
			(layer "F.Fab")
		)
		(fp_line
			(start 0.2794 -0.1016)
			(end -0.2794 -0.1016)
			(stroke
				(width 0.1)
				(type default)
			)
			(layer "F.Fab")
		)
		(fp_line
			(start -0.2794 0.9906)
			(end 0.2794 0.9906)
			(stroke
				(width 0.1)
				(type default)
			)
			(layer "F.Fab")
		)
		(fp_line
			(start -0.2794 -0.1016)
			(end -0.2794 0.9906)
			(stroke
				(width 0.1)
				(type default)
			)
			(layer "F.Fab")
		)
		(pad "1" smd rect
			(at 0 0 180)
			(size 0.508 0.508)
			(layers "F.Cu" "F.Mask" "F.Paste")
			(net "P3V3_STBY")
		)
		(pad "2" smd rect
			(at 0 0.889 180)
			(size 0.508 0.508)
			(layers "F.Cu" "F.Mask" "F.Paste")
			(net "FM_OC_DETECT_N")
		)
		(zone
			(layer "F.Cu")
			(hatch none 0.5)
			(connect_pads
				(clearance 0)
			)
			(min_thickness 0.25)
			(keepout
				(tracks not_allowed)
				(vias allowed)
				(pads allowed)
				(copperpour not_allowed)
				(footprints allowed)
			)
			(placement
				(enabled no)
				(sheetname "")
			)
			(fill
				(thermal_gap 0.5)
				(thermal_bridge_width 0.5)
				(island_removal_mode 0)
			)
			(polygon
				(pts
					(xy 26.543 -81.661) (xy 26.035 -81.661) (xy 26.035 -81.28) (xy 26.543 -81.28)
				)
			)
		)
		(zone
			(layer "F.Cu")
			(hatch none 0.5)
			(connect_pads
				(clearance 0)
			)
			(min_thickness 0.25)
			(keepout
				(tracks allowed)
				(vias not_allowed)
				(pads allowed)
				(copperpour not_allowed)
				(footprints allowed)
			)
			(placement
				(enabled no)
				(sheetname "")
			)
			(fill
				(thermal_gap 0.5)
				(thermal_bridge_width 0.5)
				(island_removal_mode 0)
			)
			(polygon
				(pts
					(xy 26.543 -81.28) (xy 26.035 -81.28) (xy 26.035 -81.661) (xy 26.543 -81.661)
				)
			)
		)
	)
	(footprint ""
		(layer "F.Cu")
		(at 400.430492 -10.917936)
		(property "Reference" "C8G1"
			(at 0 0 0)
			(layer "F.SilkS")
			(hide yes)
			(effects
				(font
					(size 1.27 1.27)
				)
			)
		)
		(property "Value" ""
			(at 0 0 0)
			(layer "F.Fab")
			(effects
				(font
					(size 1.27 1.27)
				)
			)
		)
		(duplicate_pad_numbers_are_jumpers no)
		(fp_rect
			(start -0.3048 0.9906)
			(end 0.3048 -0.1016)
			(stroke
				(width 0)
				(type default)
			)
			(fill no)
			(layer "F.CrtYd")
		)
		(fp_line
			(start -0.3048 -0.1016)
			(end -0.3048 0.9906)
			(stroke
				(width 0.1)
				(type default)
			)
			(layer "F.Fab")
		)
		(fp_line
			(start -0.3048 0.9906)
			(end 0.3048 0.9906)
			(stroke
				(width 0.1)
				(type default)
			)
			(layer "F.Fab")
		)
		(fp_line
			(start 0.3048 -0.1016)
			(end -0.3048 -0.1016)
			(stroke
				(width 0.1)
				(type default)
			)
			(layer "F.Fab")
		)
		(fp_line
			(start 0.3048 0.9906)
			(end 0.3048 -0.1016)
			(stroke
				(width 0.1)
				(type default)
			)
			(layer "F.Fab")
		)
		(pad "1" smd rect
			(at 0 0)
			(size 0.508 0.508)
			(layers "F.Cu" "F.Mask" "F.Paste")
			(net "P3E_CPU0_PE2_SS_TXP<4>")
		)
		(pad "2" smd rect
			(at 0 0.889)
			(size 0.508 0.508)
			(layers "F.Cu" "F.Mask" "F.Paste")
			(net "P3E_CPU0_PE2_SS_C_TXP<4>")
		)
		(zone
			(layer "F.Cu")
			(hatch none 0.5)
			(connect_pads
				(clearance 0)
			)
			(min_thickness 0.25)
			(keepout
				(tracks allowed)
				(vias not_allowed)
				(pads allowed)
				(copperpour not_allowed)
				(footprints allowed)
			)
			(placement
				(enabled no)
				(sheetname "")
			)
			(fill
				(thermal_gap 0.5)
				(thermal_bridge_width 0.5)
				(island_removal_mode 0)
			)
			(polygon
				(pts
					(xy 400.176492 -10.282936) (xy 400.684492 -10.282936) (xy 400.684492 -10.663936) (xy 400.176492 -10.663936)
				)
			)
		)
		(zone
			(layer "F.Cu")
			(hatch none 0.5)
			(connect_pads
				(clearance 0)
			)
			(min_thickness 0.25)
			(keepout
				(tracks not_allowed)
				(vias allowed)
				(pads allowed)
				(copperpour not_allowed)
				(footprints allowed)
			)
			(placement
				(enabled no)
				(sheetname "")
			)
			(fill
				(thermal_gap 0.5)
				(thermal_bridge_width 0.5)
				(island_removal_mode 0)
			)
			(polygon
				(pts
					(xy 400.176492 -10.282936) (xy 400.684492 -10.282936) (xy 400.684492 -10.663936) (xy 400.176492 -10.663936)
				)
			)
		)
	)
	(footprint ""
		(layer "F.Cu")
		(at -1.033526 -124.073666 90)
		(property "Reference" "RF21"
			(at -0.8382 -0.67818 90)
			(unlocked yes)
			(layer "F.SilkS")
			(effects
				(font
					(size 0.4064 0.254)
					(thickness 0.1524)
				)
				(justify left)
			)
		)
		(property "Value" ""
			(at 0 0 90)
			(layer "F.Fab")
			(effects
				(font
					(size 1.27 1.27)
				)
			)
		)
		(duplicate_pad_numbers_are_jumpers no)
		(fp_poly
			(pts
				(xy -0.2794 -0.1016) (xy 0.2794 -0.1016) (xy 0.2794 0.9906) (xy -0.2794 0.9906)
			)
			(stroke
				(width 0)
				(type default)
			)
			(fill no)
			(layer "F.CrtYd")
		)
		(fp_line
			(start 0.2794 -0.1016)
			(end -0.2794 -0.1016)
			(stroke
				(width 0.1)
				(type default)
			)
			(layer "F.Fab")
		)
		(fp_line
			(start -0.2794 -0.1016)
			(end -0.2794 0.9906)
			(stroke
				(width 0.1)
				(type default)
			)
			(layer "F.Fab")
		)
		(fp_line
			(start 0.2794 0.9906)
			(end 0.2794 -0.1016)
			(stroke
				(width 0.1)
				(type default)
			)
			(layer "F.Fab")
		)
		(fp_line
			(start -0.2794 0.9906)
			(end 0.2794 0.9906)
			(stroke
				(width 0.1)
				(type default)
			)
			(layer "F.Fab")
		)
		(pad "1" smd rect
			(at 0 0 90)
			(size 0.508 0.508)
			(layers "F.Cu" "F.Mask" "F.Paste")
			(net "VR_PVDDQ_KLM_AIREF1")
		)
		(pad "2" smd rect
			(at 0 0.889 90)
			(size 0.508 0.508)
			(layers "F.Cu" "F.Mask" "F.Paste")
			(net "ISENSE_PVDDQ_KLM_PH1_IMON")
		)
		(zone
			(layer "F.Cu")
			(hatch none 0.5)
			(connect_pads
				(clearance 0)
			)
			(min_thickness 0.25)
			(keepout
				(tracks allowed)
				(vias not_allowed)
				(pads allowed)
				(copperpour not_allowed)
				(footprints allowed)
			)
			(placement
				(enabled no)
				(sheetname "")
			)
			(fill
				(thermal_gap 0.5)
				(thermal_bridge_width 0.5)
				(island_removal_mode 0)
			)
			(polygon
				(pts
					(xy -0.779526 -123.819666) (xy -0.779526 -124.327666) (xy -0.398526 -124.327666) (xy -0.398526 -123.819666)
				)
			)
		)
		(zone
			(layer "F.Cu")
			(hatch none 0.5)
			(connect_pads
				(clearance 0)
			)
			(min_thickness 0.25)
			(keepout
				(tracks not_allowed)
				(vias allowed)
				(pads allowed)
				(copperpour not_allowed)
				(footprints allowed)
			)
			(placement
				(enabled no)
				(sheetname "")
			)
			(fill
				(thermal_gap 0.5)
				(thermal_bridge_width 0.5)
				(island_removal_mode 0)
			)
			(polygon
				(pts
					(xy -0.398526 -123.819666) (xy -0.398526 -124.327666) (xy -0.779526 -124.327666) (xy -0.779526 -123.819666)
				)
			)
		)
	)
)
